(kicad_pcb
	(version 20260206)
	(generator "pcbnew")
	(generator_version "10.0")
	(general
		(thickness 1.6)
		(legacy_teardrops no)
	)
	(paper "A4")
	(title_block
		(title "Wiwynn_Tioga_Pass_MB.brd")
		(comment 1 "Tioga Pass / footprints 2157-2163 of 4770")
	)
	(layers
		(0 "F.Cu" signal "TOP")
		(4 "In1.Cu" signal "L2GND")
		(6 "In2.Cu" signal "L3")
		(8 "In3.Cu" signal "L4GND")
		(10 "In4.Cu" signal "L5")
		(12 "In5.Cu" signal "L6GND")
		(14 "In6.Cu" signal "L7VCC")
		(16 "In7.Cu" signal "L8VCC")
		(18 "In8.Cu" signal "L9GND")
		(20 "In9.Cu" signal "L10")
		(22 "In10.Cu" signal "L11GND")
		(24 "In11.Cu" signal "L12")
		(26 "In12.Cu" signal "L13GND")
		(2 "B.Cu" signal "BOTTOM")
		(9 "F.Adhes" user "F.Adhesive")
		(11 "B.Adhes" user "B.Adhesive")
		(13 "F.Paste" user "Package Geometry/Pastemask Top")
		(15 "B.Paste" user "Package Geometry/Pastemask Bottom")
		(5 "F.SilkS" user "Ref Des/Silkscreen Top")
		(7 "B.SilkS" user "Ref Des/Silkscreen Bottom")
		(1 "F.Mask" user "Board Geometry/Soldermask Top")
		(3 "B.Mask" user "Board Geometry/Soldermask Bottom")
		(17 "Dwgs.User" user "User.Drawings")
		(19 "Cmts.User" user "User.Comments")
		(21 "Eco1.User" user "User.Eco1")
		(23 "Eco2.User" user "User.Eco2")
		(25 "Edge.Cuts" user "Board Geometry/Outline")
		(27 "Margin" user)
		(31 "F.CrtYd" user "Package Geometry/Place Bound Top")
		(29 "B.CrtYd" user "Package Geometry/Place Bound Bottom")
		(35 "F.Fab" user "Ref Des/Assembly Top")
		(33 "B.Fab" user "Ref Des/Assembly Bottom")
	)
	(footprint ""
		(layer "F.Cu")
		(at 429.54448 -14.605 180)
		(property "Reference" "U6W11"
			(at 0 0 180)
			(layer "F.SilkS")
			(hide yes)
			(effects
				(font
					(size 1.27 1.27)
				)
			)
		)
		(property "Value" "*"
			(at 0.127 -12.51585 180)
			(unlocked yes)
			(layer "F.Fab")
			(hide yes)
			(effects
				(font
					(size 0.889 0.889)
					(thickness 0.1524)
				)
			)
		)
		(property "Device Type" "PCA9554PWR-GP_DISCRET-G1-PCA95A"
			(at 0.1016 -14.52245 180)
			(unlocked yes)
			(layer "F.Fab")
			(hide yes)
			(effects
				(font
					(size 0.889 0.889)
					(thickness 0.1524)
				)
			)
		)
		(duplicate_pad_numbers_are_jumpers no)
		(fp_line
			(start 2.3622 1.778)
			(end -2.921 1.778)
			(stroke
				(width 0.1524)
				(type default)
			)
			(layer "F.SilkS")
		)
		(fp_line
			(start 2.3622 -1.778)
			(end 2.3622 1.778)
			(stroke
				(width 0.1524)
				(type default)
			)
			(layer "F.SilkS")
		)
		(fp_line
			(start -2.54 0)
			(end -3.0988 0.5588)
			(stroke
				(width 0.1524)
				(type default)
			)
			(layer "F.SilkS")
		)
		(fp_line
			(start -2.54 0)
			(end -3.0988 -0.5588)
			(stroke
				(width 0.1524)
				(type default)
			)
			(layer "F.SilkS")
		)
		(fp_line
			(start -2.921 3.81)
			(end -2.921 1.778)
			(stroke
				(width 0.508)
				(type default)
			)
			(layer "F.SilkS")
		)
		(fp_line
			(start -3.0988 -1.778)
			(end 2.3622 -1.778)
			(stroke
				(width 0.1524)
				(type default)
			)
			(layer "F.SilkS")
		)
		(fp_line
			(start -3.0988 -1.778)
			(end -3.0988 1.778)
			(stroke
				(width 0.1524)
				(type default)
			)
			(layer "F.SilkS")
		)
		(fp_poly
			(pts
				(xy -2.4638 -1.778) (xy -2.4638 1.778) (xy 2.3622 1.778) (xy 2.3622 -1.778)
			)
			(stroke
				(width 0)
				(type default)
			)
			(fill yes)
			(layer "F.SilkS")
		)
		(fp_rect
			(start -3.175 4.064)
			(end 3.175 -4.064)
			(stroke
				(width 0)
				(type default)
			)
			(fill no)
			(layer "F.CrtYd")
		)
		(fp_poly
			(pts
				(xy -3.175 -4.064) (xy 3.175 -4.064) (xy 3.175 4.064) (xy -3.175 4.064)
			)
			(stroke
				(width 0)
				(type default)
			)
			(fill no)
			(layer "F.Fab")
		)
		(pad "1" smd rect
			(at -2.27584 2.8194 180)
			(size 0.3556 1.524)
			(layers "F.Cu" "F.Mask" "F.Paste")
			(net "PCA9554_A0")
		)
		(pad "2" smd rect
			(at -1.6256 2.8194 180)
			(size 0.3556 1.524)
			(layers "F.Cu" "F.Mask" "F.Paste")
			(net "PCA9554_A1")
		)
		(pad "3" smd rect
			(at -0.97536 2.8194 180)
			(size 0.3556 1.524)
			(layers "F.Cu" "F.Mask" "F.Paste")
			(net "PCA9554_A2")
		)
		(pad "4" smd rect
			(at -0.32512 2.8194 180)
			(size 0.3556 1.524)
			(layers "F.Cu" "F.Mask" "F.Paste")
			(net "FM_MB_SLOT_ID0")
		)
		(pad "5" smd rect
			(at 0.32512 2.8194 180)
			(size 0.3556 1.524)
			(layers "F.Cu" "F.Mask" "F.Paste")
			(net "FM_MB_SLOT_ID1")
		)
		(pad "6" smd rect
			(at 0.97536 2.8194 180)
			(size 0.3556 1.524)
			(layers "F.Cu" "F.Mask" "F.Paste")
			(net "FM_MB_SLOT_ID2")
		)
		(pad "7" smd rect
			(at 1.6256 2.8194 180)
			(size 0.3556 1.524)
			(layers "F.Cu" "F.Mask" "F.Paste")
			(net "FM_CPU_BMC_INIT")
		)
		(pad "8" smd rect
			(at 2.27584 2.8194 180)
			(size 0.3556 1.524)
			(layers "F.Cu" "F.Mask" "F.Paste")
			(net "GND")
		)
		(pad "9" smd rect
			(at 2.27584 -2.8194 180)
			(size 0.3556 1.524)
			(layers "F.Cu" "F.Mask" "F.Paste")
			(net "Net_6513")
		)
		(pad "10" smd rect
			(at 1.6256 -2.8194 180)
			(size 0.3556 1.524)
			(layers "F.Cu" "F.Mask" "F.Paste")
			(net "Net_6512")
		)
		(pad "11" smd rect
			(at 0.97536 -2.8194 180)
			(size 0.3556 1.524)
			(layers "F.Cu" "F.Mask" "F.Paste")
			(net "Net_6511")
		)
		(pad "12" smd rect
			(at 0.32512 -2.8194 180)
			(size 0.3556 1.524)
			(layers "F.Cu" "F.Mask" "F.Paste")
			(net "Net_6510")
		)
		(pad "13" smd rect
			(at -0.32512 -2.8194 180)
			(size 0.3556 1.524)
			(layers "F.Cu" "F.Mask" "F.Paste")
			(net "PCA9554_INT_N")
		)
		(pad "14" smd rect
			(at -0.97536 -2.8194 180)
			(size 0.3556 1.524)
			(layers "F.Cu" "F.Mask" "F.Paste")
			(net "SMB_SENSOR_STBY_LVC3_SCL")
		)
		(pad "15" smd rect
			(at -1.6256 -2.8194 180)
			(size 0.3556 1.524)
			(layers "F.Cu" "F.Mask" "F.Paste")
			(net "SMB_SENSOR_STBY_LVC3_SDA")
		)
		(pad "16" smd rect
			(at -2.27584 -2.8194 180)
			(size 0.3556 1.524)
			(layers "F.Cu" "F.Mask" "F.Paste")
			(net "P3V3_STBY")
		)
	)
	(footprint ""
		(layer "F.Cu")
		(at 320.194432 -149.86 90)
		(property "Reference" "C6A3"
			(at 0 0 90)
			(layer "F.SilkS")
			(hide yes)
			(effects
				(font
					(size 1.27 1.27)
				)
			)
		)
		(property "Value" ""
			(at 0 0 90)
			(layer "F.Fab")
			(effects
				(font
					(size 1.27 1.27)
				)
			)
		)
		(duplicate_pad_numbers_are_jumpers no)
		(fp_poly
			(pts
				(xy -0.4953 -0.2032) (xy 0.4953 -0.2032) (xy 0.4953 1.6002) (xy -0.4953 1.6002)
			)
			(stroke
				(width 0)
				(type default)
			)
			(fill no)
			(layer "F.CrtYd")
		)
		(fp_line
			(start 0.4953 -0.2032)
			(end 0.4953 1.6002)
			(stroke
				(width 0.1)
				(type default)
			)
			(layer "F.Fab")
		)
		(fp_line
			(start -0.4953 -0.2032)
			(end 0.4953 -0.2032)
			(stroke
				(width 0.1)
				(type default)
			)
			(layer "F.Fab")
		)
		(fp_line
			(start 0.4953 1.6002)
			(end -0.4953 1.6002)
			(stroke
				(width 0.1)
				(type default)
			)
			(layer "F.Fab")
		)
		(fp_line
			(start -0.4953 1.6002)
			(end -0.4953 -0.2032)
			(stroke
				(width 0.1)
				(type default)
			)
			(layer "F.Fab")
		)
		(pad "1" smd rect
			(at 0 0 90)
			(size 0.762 0.889)
			(layers "F.Cu" "F.Mask" "F.Paste")
			(net "PVPP_DEF")
		)
		(pad "2" smd rect
			(at 0 1.397 90)
			(size 0.762 0.889)
			(layers "F.Cu" "F.Mask" "F.Paste")
			(net "GND")
		)
		(zone
			(layer "F.Cu")
			(hatch none 0.5)
			(connect_pads
				(clearance 0)
			)
			(min_thickness 0.25)
			(keepout
				(tracks not_allowed)
				(vias allowed)
				(pads allowed)
				(copperpour not_allowed)
				(footprints allowed)
			)
			(placement
				(enabled no)
				(sheetname "")
			)
			(fill
				(thermal_gap 0.5)
				(thermal_bridge_width 0.5)
				(island_removal_mode 0)
			)
			(polygon
				(pts
					(xy 320.638932 -149.479) (xy 320.638932 -150.241) (xy 321.146932 -150.241) (xy 321.146932 -149.479)
				)
			)
		)
	)
	(footprint ""
		(layer "F.Cu")
		(at 278.070056 -69.969888)
		(property "Reference" "R6D14"
			(at 0 0 0)
			(layer "F.SilkS")
			(hide yes)
			(effects
				(font
					(size 1.27 1.27)
				)
			)
		)
		(property "Value" ""
			(at 0 0 0)
			(layer "F.Fab")
			(effects
				(font
					(size 1.27 1.27)
				)
			)
		)
		(duplicate_pad_numbers_are_jumpers no)
		(fp_poly
			(pts
				(xy -0.2794 -0.1016) (xy 0.2794 -0.1016) (xy 0.2794 0.9906) (xy -0.2794 0.9906)
			)
			(stroke
				(width 0)
				(type default)
			)
			(fill no)
			(layer "F.CrtYd")
		)
		(fp_line
			(start -0.2794 -0.1016)
			(end -0.2794 0.9906)
			(stroke
				(width 0.1)
				(type default)
			)
			(layer "F.Fab")
		)
		(fp_line
			(start -0.2794 0.9906)
			(end 0.2794 0.9906)
			(stroke
				(width 0.1)
				(type default)
			)
			(layer "F.Fab")
		)
		(fp_line
			(start 0.2794 -0.1016)
			(end -0.2794 -0.1016)
			(stroke
				(width 0.1)
				(type default)
			)
			(layer "F.Fab")
		)
		(fp_line
			(start 0.2794 0.9906)
			(end 0.2794 -0.1016)
			(stroke
				(width 0.1)
				(type default)
			)
			(layer "F.Fab")
		)
		(pad "1" smd rect
			(at 0 0)
			(size 0.508 0.508)
			(layers "F.Cu" "F.Mask" "F.Paste")
			(net "GND")
		)
		(pad "2" smd rect
			(at 0 0.889)
			(size 0.508 0.508)
			(layers "F.Cu" "F.Mask" "F.Paste")
			(net "PD_CPU0_EAR_N")
		)
		(zone
			(layer "F.Cu")
			(hatch none 0.5)
			(connect_pads
				(clearance 0)
			)
			(min_thickness 0.25)
			(keepout
				(tracks allowed)
				(vias not_allowed)
				(pads allowed)
				(copperpour not_allowed)
				(footprints allowed)
			)
			(placement
				(enabled no)
				(sheetname "")
			)
			(fill
				(thermal_gap 0.5)
				(thermal_bridge_width 0.5)
				(island_removal_mode 0)
			)
			(polygon
				(pts
					(xy 277.816056 -69.715888) (xy 278.324056 -69.715888) (xy 278.324056 -69.334888) (xy 277.816056 -69.334888)
				)
			)
		)
		(zone
			(layer "F.Cu")
			(hatch none 0.5)
			(connect_pads
				(clearance 0)
			)
			(min_thickness 0.25)
			(keepout
				(tracks not_allowed)
				(vias allowed)
				(pads allowed)
				(copperpour not_allowed)
				(footprints allowed)
			)
			(placement
				(enabled no)
				(sheetname "")
			)
			(fill
				(thermal_gap 0.5)
				(thermal_bridge_width 0.5)
				(island_removal_mode 0)
			)
			(polygon
				(pts
					(xy 277.816056 -69.334888) (xy 278.324056 -69.334888) (xy 278.324056 -69.715888) (xy 277.816056 -69.715888)
				)
			)
		)
	)
	(footprint ""
		(layer "F.Cu")
		(at 411.48 -87.8205 180)
		(property "Reference" "C2R6"
			(at 0 0 180)
			(layer "F.SilkS")
			(hide yes)
			(effects
				(font
					(size 1.27 1.27)
				)
			)
		)
		(property "Value" ""
			(at 0 0 180)
			(layer "F.Fab")
			(effects
				(font
					(size 1.27 1.27)
				)
			)
		)
		(duplicate_pad_numbers_are_jumpers no)
		(fp_poly
			(pts
				(xy 0.3048 -0.1016) (xy 0.3048 0.9906) (xy -0.3048 0.9906) (xy -0.3048 -0.1016)
			)
			(stroke
				(width 0)
				(type default)
			)
			(fill no)
			(layer "F.CrtYd")
		)
		(fp_line
			(start 0.3048 0.9906)
			(end 0.3048 -0.1016)
			(stroke
				(width 0.1)
				(type default)
			)
			(layer "F.Fab")
		)
		(fp_line
			(start 0.3048 -0.1016)
			(end -0.3048 -0.1016)
			(stroke
				(width 0.1)
				(type default)
			)
			(layer "F.Fab")
		)
		(fp_line
			(start -0.3048 0.9906)
			(end 0.3048 0.9906)
			(stroke
				(width 0.1)
				(type default)
			)
			(layer "F.Fab")
		)
		(fp_line
			(start -0.3048 -0.1016)
			(end -0.3048 0.9906)
			(stroke
				(width 0.1)
				(type default)
			)
			(layer "F.Fab")
		)
		(pad "1" smd rect
			(at 0 0 180)
			(size 0.508 0.508)
			(layers "F.Cu" "F.Mask" "F.Paste")
			(net "FM_PS_EN")
		)
		(pad "2" smd rect
			(at 0 0.889 180)
			(size 0.508 0.508)
			(layers "F.Cu" "F.Mask" "F.Paste")
			(net "GND")
		)
		(zone
			(layer "F.Cu")
			(hatch none 0.5)
			(connect_pads
				(clearance 0)
			)
			(min_thickness 0.25)
			(keepout
				(tracks not_allowed)
				(vias allowed)
				(pads allowed)
				(copperpour not_allowed)
				(footprints allowed)
			)
			(placement
				(enabled no)
				(sheetname "")
			)
			(fill
				(thermal_gap 0.5)
				(thermal_bridge_width 0.5)
				(island_removal_mode 0)
			)
			(polygon
				(pts
					(xy 411.734 -88.4555) (xy 411.226 -88.4555) (xy 411.226 -88.0745) (xy 411.734 -88.0745)
				)
			)
		)
		(zone
			(layer "F.Cu")
			(hatch none 0.5)
			(connect_pads
				(clearance 0)
			)
			(min_thickness 0.25)
			(keepout
				(tracks allowed)
				(vias not_allowed)
				(pads allowed)
				(copperpour not_allowed)
				(footprints allowed)
			)
			(placement
				(enabled no)
				(sheetname "")
			)
			(fill
				(thermal_gap 0.5)
				(thermal_bridge_width 0.5)
				(island_removal_mode 0)
			)
			(polygon
				(pts
					(xy 411.734 -88.0745) (xy 411.226 -88.0745) (xy 411.226 -88.4555) (xy 411.734 -88.4555)
				)
			)
		)
	)
	(footprint ""
		(layer "F.Cu")
		(at 486.687876 -27.227784 180)
		(property "Reference" "R9F69"
			(at 0 0 180)
			(layer "F.SilkS")
			(hide yes)
			(effects
				(font
					(size 1.27 1.27)
				)
			)
		)
		(property "Value" ""
			(at 0 0 180)
			(layer "F.Fab")
			(effects
				(font
					(size 1.27 1.27)
				)
			)
		)
		(duplicate_pad_numbers_are_jumpers no)
		(fp_poly
			(pts
				(xy -0.2794 -0.1016) (xy 0.2794 -0.1016) (xy 0.2794 0.9906) (xy -0.2794 0.9906)
			)
			(stroke
				(width 0)
				(type default)
			)
			(fill no)
			(layer "F.CrtYd")
		)
		(fp_line
			(start 0.2794 0.9906)
			(end 0.2794 -0.1016)
			(stroke
				(width 0.1)
				(type default)
			)
			(layer "F.Fab")
		)
		(fp_line
			(start 0.2794 -0.1016)
			(end -0.2794 -0.1016)
			(stroke
				(width 0.1)
				(type default)
			)
			(layer "F.Fab")
		)
		(fp_line
			(start -0.2794 0.9906)
			(end 0.2794 0.9906)
			(stroke
				(width 0.1)
				(type default)
			)
			(layer "F.Fab")
		)
		(fp_line
			(start -0.2794 -0.1016)
			(end -0.2794 0.9906)
			(stroke
				(width 0.1)
				(type default)
			)
			(layer "F.Fab")
		)
		(pad "1" smd rect
			(at 0 0 180)
			(size 0.508 0.508)
			(layers "F.Cu" "F.Mask" "F.Paste")
			(net "SP2_BMC_CM_UART_RX_R")
		)
		(pad "2" smd rect
			(at 0 0.889 180)
			(size 0.508 0.508)
			(layers "F.Cu" "F.Mask" "F.Paste")
			(net "SP2_BMC_CM_UART_RX_R1")
		)
		(zone
			(layer "F.Cu")
			(hatch none 0.5)
			(connect_pads
				(clearance 0)
			)
			(min_thickness 0.25)
			(keepout
				(tracks not_allowed)
				(vias allowed)
				(pads allowed)
				(copperpour not_allowed)
				(footprints allowed)
			)
			(placement
				(enabled no)
				(sheetname "")
			)
			(fill
				(thermal_gap 0.5)
				(thermal_bridge_width 0.5)
				(island_removal_mode 0)
			)
			(polygon
				(pts
					(xy 486.941876 -27.862784) (xy 486.433876 -27.862784) (xy 486.433876 -27.481784) (xy 486.941876 -27.481784)
				)
			)
		)
		(zone
			(layer "F.Cu")
			(hatch none 0.5)
			(connect_pads
				(clearance 0)
			)
			(min_thickness 0.25)
			(keepout
				(tracks allowed)
				(vias not_allowed)
				(pads allowed)
				(copperpour not_allowed)
				(footprints allowed)
			)
			(placement
				(enabled no)
				(sheetname "")
			)
			(fill
				(thermal_gap 0.5)
				(thermal_bridge_width 0.5)
				(island_removal_mode 0)
			)
			(polygon
				(pts
					(xy 486.941876 -27.481784) (xy 486.433876 -27.481784) (xy 486.433876 -27.862784) (xy 486.941876 -27.862784)
				)
			)
		)
	)
	(footprint ""
		(layer "F.Cu")
		(at 168.6941 -8.763 90)
		(property "Reference" "R4G7"
			(at 0 0 90)
			(layer "F.SilkS")
			(hide yes)
			(effects
				(font
					(size 1.27 1.27)
				)
			)
		)
		(property "Value" ""
			(at 0 0 90)
			(layer "F.Fab")
			(effects
				(font
					(size 1.27 1.27)
				)
			)
		)
		(duplicate_pad_numbers_are_jumpers no)
		(fp_rect
			(start -0.2794 -0.1016)
			(end 0.2794 0.9906)
			(stroke
				(width 0)
				(type default)
			)
			(fill no)
			(layer "F.CrtYd")
		)
		(fp_line
			(start 0.2794 -0.1016)
			(end -0.2794 -0.1016)
			(stroke
				(width 0.1)
				(type default)
			)
			(layer "F.Fab")
		)
		(fp_line
			(start -0.2794 -0.1016)
			(end -0.2794 0.9906)
			(stroke
				(width 0.1)
				(type default)
			)
			(layer "F.Fab")
		)
		(fp_line
			(start 0.2794 0.9906)
			(end 0.2794 -0.1016)
			(stroke
				(width 0.1)
				(type default)
			)
			(layer "F.Fab")
		)
		(fp_line
			(start -0.2794 0.9906)
			(end 0.2794 0.9906)
			(stroke
				(width 0.1)
				(type default)
			)
			(layer "F.Fab")
		)
		(pad "1" smd rect
			(at 0 0 90)
			(size 0.508 0.508)
			(layers "F.Cu" "F.Mask" "F.Paste")
			(net "VSENSE_PVPP_GHJ")
		)
		(pad "2" smd rect
			(at 0 0.889 90)
			(size 0.508 0.508)
			(layers "F.Cu" "F.Mask" "F.Paste")
			(net "VR_FB_PVPP_GHJ")
		)
		(zone
			(layer "F.Cu")
			(hatch none 0.5)
			(connect_pads
				(clearance 0)
			)
			(min_thickness 0.25)
			(keepout
				(tracks not_allowed)
				(vias allowed)
				(pads allowed)
				(copperpour not_allowed)
				(footprints allowed)
			)
			(placement
				(enabled no)
				(sheetname "")
			)
			(fill
				(thermal_gap 0.5)
				(thermal_bridge_width 0.5)
				(island_removal_mode 0)
			)
			(polygon
				(pts
					(xy 168.9481 -8.509) (xy 169.3291 -8.509) (xy 169.3291 -9.017) (xy 168.9481 -9.017)
				)
			)
		)
		(zone
			(layer "F.Cu")
			(hatch none 0.5)
			(connect_pads
				(clearance 0)
			)
			(min_thickness 0.25)
			(keepout
				(tracks allowed)
				(vias not_allowed)
				(pads allowed)
				(copperpour not_allowed)
				(footprints allowed)
			)
			(placement
				(enabled no)
				(sheetname "")
			)
			(fill
				(thermal_gap 0.5)
				(thermal_bridge_width 0.5)
				(island_removal_mode 0)
			)
			(polygon
				(pts
					(xy 168.9481 -8.509) (xy 169.3291 -8.509) (xy 169.3291 -9.017) (xy 168.9481 -9.017)
				)
			)
		)
	)
	(footprint ""
		(layer "F.Cu")
		(at 188.500512 -67.920108 180)
		(property "Reference" "RF3"
			(at -0.8382 -0.67818 180)
			(unlocked yes)
			(layer "F.SilkS")
			(effects
				(font
					(size 0.4064 0.254)
					(thickness 0.1524)
				)
				(justify left)
			)
		)
		(property "Value" ""
			(at 0 0 180)
			(layer "F.Fab")
			(effects
				(font
					(size 1.27 1.27)
				)
			)
		)
		(duplicate_pad_numbers_are_jumpers no)
		(fp_poly
			(pts
				(xy -0.2794 -0.1016) (xy 0.2794 -0.1016) (xy 0.2794 0.9906) (xy -0.2794 0.9906)
			)
			(stroke
				(width 0)
				(type default)
			)
			(fill no)
			(layer "F.CrtYd")
		)
		(fp_line
			(start 0.2794 0.9906)
			(end 0.2794 -0.1016)
			(stroke
				(width 0.1)
				(type default)
			)
			(layer "F.Fab")
		)
		(fp_line
			(start 0.2794 -0.1016)
			(end -0.2794 -0.1016)
			(stroke
				(width 0.1)
				(type default)
			)
			(layer "F.Fab")
		)
		(fp_line
			(start -0.2794 0.9906)
			(end 0.2794 0.9906)
			(stroke
				(width 0.1)
				(type default)
			)
			(layer "F.Fab")
		)
		(fp_line
			(start -0.2794 -0.1016)
			(end -0.2794 0.9906)
			(stroke
				(width 0.1)
				(type default)
			)
			(layer "F.Fab")
		)
		(pad "1" smd rect
			(at 0 0 180)
			(size 0.508 0.508)
			(layers "F.Cu" "F.Mask" "F.Paste")
			(net "VR_PVCCIN_CPU0_AIREF3")
		)
		(pad "2" smd rect
			(at 0 0.889 180)
			(size 0.508 0.508)
			(layers "F.Cu" "F.Mask" "F.Paste")
			(net "ISENSE_PVCCIN_CPU0_PH3_IMON")
		)
		(zone
			(layer "F.Cu")
			(hatch none 0.5)
			(connect_pads
				(clearance 0)
			)
			(min_thickness 0.25)
			(keepout
				(tracks not_allowed)
				(vias allowed)
				(pads allowed)
				(copperpour not_allowed)
				(footprints allowed)
			)
			(placement
				(enabled no)
				(sheetname "")
			)
			(fill
				(thermal_gap 0.5)
				(thermal_bridge_width 0.5)
				(island_removal_mode 0)
			)
			(polygon
				(pts
					(xy 188.754512 -68.555108) (xy 188.246512 -68.555108) (xy 188.246512 -68.174108) (xy 188.754512 -68.174108)
				)
			)
		)
		(zone
			(layer "F.Cu")
			(hatch none 0.5)
			(connect_pads
				(clearance 0)
			)
			(min_thickness 0.25)
			(keepout
				(tracks allowed)
				(vias not_allowed)
				(pads allowed)
				(copperpour not_allowed)
				(footprints allowed)
			)
			(placement
				(enabled no)
				(sheetname "")
			)
			(fill
				(thermal_gap 0.5)
				(thermal_bridge_width 0.5)
				(island_removal_mode 0)
			)
			(polygon
				(pts
					(xy 188.754512 -68.174108) (xy 188.246512 -68.174108) (xy 188.246512 -68.555108) (xy 188.754512 -68.555108)
				)
			)
		)
	)
)
